(kicad_pcb
	(version 20260206)
	(generator "pcbnew")
	(generator_version "10.0")
	(general
		(thickness 1.6)
		(legacy_teardrops no)
	)
	(paper "A4")
	(title_block
		(title "Bryce Canyon_IOM_M2_16342-2_OCP.brd")
		(comment 1 "Bryce Canyon / footprints 192-198 of 1146")
	)
	(layers
		(0 "F.Cu" signal "TOP")
		(4 "In1.Cu" signal "L2GND")
		(6 "In2.Cu" signal "L3")
		(8 "In3.Cu" signal "L4VCC")
		(10 "In4.Cu" signal "L5VCC")
		(12 "In5.Cu" signal "L6")
		(14 "In6.Cu" signal "L7GND")
		(2 "B.Cu" signal "BOTTOM")
		(9 "F.Adhes" user "F.Adhesive")
		(11 "B.Adhes" user "B.Adhesive")
		(13 "F.Paste" user "Package Geometry/Pastemask Top")
		(15 "B.Paste" user "Package Geometry/Pastemask Bottom")
		(5 "F.SilkS" user "Ref Des/Silkscreen Top")
		(7 "B.SilkS" user "Ref Des/Silkscreen Bottom")
		(1 "F.Mask" user "Board Geometry/Soldermask Top")
		(3 "B.Mask" user "Board Geometry/Soldermask Bottom")
		(17 "Dwgs.User" user "User.Drawings")
		(19 "Cmts.User" user "User.Comments")
		(21 "Eco1.User" user "User.Eco1")
		(23 "Eco2.User" user "User.Eco2")
		(25 "Edge.Cuts" user "Board Geometry/Outline")
		(27 "Margin" user)
		(31 "F.CrtYd" user "Package Geometry/Place Bound Top")
		(29 "B.CrtYd" user "Package Geometry/Place Bound Bottom")
		(35 "F.Fab" user "Ref Des/Assembly Top")
		(33 "B.Fab" user "Ref Des/Assembly Bottom")
	)
	(footprint ""
		(layer "F.Cu")
		(at 149.516338 -8.586978)
		(property "Reference" "G5"
			(at 0 0 0)
			(layer "F.SilkS")
			(hide yes)
			(effects
				(font
					(size 1.27 1.27)
				)
			)
		)
		(property "Value" "COPPER-CLOSE-GP-U"
			(at 0.0762 -2.8702 0)
			(unlocked yes)
			(layer "F.Fab")
			(hide yes)
			(effects
				(font
					(size 1.016 1.016)
					(thickness 0.1524)
				)
			)
		)
		(property "Device Type" "CON2C-U"
			(at 0.0762 -4.3942 0)
			(unlocked yes)
			(layer "F.Fab")
			(hide yes)
			(effects
				(font
					(size 1.016 1.016)
					(thickness 0.1524)
				)
			)
		)
		(duplicate_pad_numbers_are_jumpers no)
		(fp_rect
			(start -0.9398 0.9652)
			(end 0.9398 -0.9652)
			(stroke
				(width 0)
				(type default)
			)
			(fill no)
			(layer "F.CrtYd")
		)
		(fp_rect
			(start -0.9398 0.9652)
			(end 0.9398 -0.9652)
			(stroke
				(width 0)
				(type default)
			)
			(fill no)
			(layer "F.Fab")
		)
		(pad "1" smd custom
			(at 0 -0.5334)
			(size 0.17145 0.17145)
			(layers "F.Cu" "F.Mask" "F.Paste")
			(net "AGND_P1V8_STBY")
			(options
				(clearance outline)
				(anchor circle)
			)
			(primitives
				(gr_poly
					(pts
						(xy -0.127 0.3429) (xy -0.127 0.1651) (xy -0.635 -0.3429) (xy 0.635 -0.3429) (xy 0.127 0.1651)
						(xy 0.127 0.3429)
					)
					(width 0)
					(fill yes)
				)
			)
		)
		(pad "2" smd custom
			(at 0 0.5334)
			(size 0.17145 0.17145)
			(layers "F.Cu" "F.Mask" "F.Paste")
			(net "GND")
			(options
				(clearance outline)
				(anchor circle)
			)
			(primitives
				(gr_poly
					(pts
						(xy -0.635 0.3429) (xy -0.127 -0.1651) (xy -0.127 -0.3429) (xy 0.127 -0.3429) (xy 0.127 -0.1651)
						(xy 0.635 0.3429)
					)
					(width 0)
					(fill yes)
				)
			)
		)
	)
	(footprint ""
		(layer "F.Cu")
		(at 53.848 -127.254 180)
		(property "Reference" "R610"
			(at 0 0 180)
			(layer "F.SilkS")
			(hide yes)
			(effects
				(font
					(size 1.27 1.27)
				)
			)
		)
		(property "Value" "100KR2F-L1-GP"
			(at 0.064008 -3.993896 180)
			(unlocked yes)
			(layer "F.Fab")
			(hide yes)
			(effects
				(font
					(size 1.016 1.016)
					(thickness 0.1524)
				)
			)
		)
		(property "Device Type" "R402H16"
			(at 0.064008 -5.517896 180)
			(unlocked yes)
			(layer "F.Fab")
			(hide yes)
			(effects
				(font
					(size 1.016 1.016)
					(thickness 0.1524)
				)
			)
		)
		(duplicate_pad_numbers_are_jumpers no)
		(fp_line
			(start 0.508 -0.9398)
			(end -0.508 -0.9398)
			(stroke
				(width 0.1524)
				(type default)
			)
			(layer "F.SilkS")
		)
		(fp_line
			(start -0.508 -0.9398)
			(end -0.508 0.9398)
			(stroke
				(width 0.1524)
				(type default)
			)
			(layer "F.SilkS")
		)
		(fp_rect
			(start -0.508 0.9398)
			(end 0.508 -0.9398)
			(stroke
				(width 0)
				(type default)
			)
			(fill no)
			(layer "F.CrtYd")
		)
		(fp_rect
			(start -0.508 0.9398)
			(end 0.508 -0.9398)
			(stroke
				(width 0)
				(type default)
			)
			(fill no)
			(layer "F.Fab")
		)
		(pad "1" smd custom
			(at 0 -0.4445 180)
			(size 0.1397 0.1397)
			(layers "F.Cu" "F.Mask" "F.Paste")
			(net "FLA1_WP_N")
			(options
				(clearance outline)
				(anchor circle)
			)
			(primitives
				(gr_poly
					(pts
						(arc
							(start -0.1778 -0.2794)
							(mid -0.249642 -0.249642)
							(end -0.2794 -0.1778)
						)
						(arc
							(start -0.2794 0.1778)
							(mid -0.249642 0.249642)
							(end -0.1778 0.2794)
						)
						(arc
							(start 0.1778 0.2794)
							(mid 0.249642 0.249642)
							(end 0.2794 0.1778)
						)
						(arc
							(start 0.2794 -0.1778)
							(mid 0.249642 -0.249642)
							(end 0.1778 -0.2794)
						)
					)
					(width 0)
					(fill yes)
				)
			)
		)
		(pad "2" smd custom
			(at 0 0.4445 180)
			(size 0.1397 0.1397)
			(layers "F.Cu" "F.Mask" "F.Paste")
			(net "GND")
			(options
				(clearance outline)
				(anchor circle)
			)
			(primitives
				(gr_poly
					(pts
						(arc
							(start -0.1778 -0.2794)
							(mid -0.249642 -0.249642)
							(end -0.2794 -0.1778)
						)
						(arc
							(start -0.2794 0.1778)
							(mid -0.249642 0.249642)
							(end -0.1778 0.2794)
						)
						(arc
							(start 0.1778 0.2794)
							(mid 0.249642 0.249642)
							(end 0.2794 0.1778)
						)
						(arc
							(start 0.2794 -0.1778)
							(mid 0.249642 -0.249642)
							(end 0.1778 -0.2794)
						)
					)
					(width 0)
					(fill yes)
				)
			)
		)
	)
	(footprint ""
		(layer "F.Cu")
		(at 82.677 -133.604 -90)
		(property "Reference" "R102"
			(at 0 0 270)
			(layer "F.SilkS")
			(hide yes)
			(effects
				(font
					(size 1.27 1.27)
				)
			)
		)
		(property "Value" "0R2J-2-GP"
			(at 0.064008 -3.993896 270)
			(unlocked yes)
			(layer "F.Fab")
			(hide yes)
			(effects
				(font
					(size 1.016 1.016)
					(thickness 0.1524)
				)
			)
		)
		(property "Device Type" "R402H16"
			(at 0.064008 -5.517896 270)
			(unlocked yes)
			(layer "F.Fab")
			(hide yes)
			(effects
				(font
					(size 1.016 1.016)
					(thickness 0.1524)
				)
			)
		)
		(duplicate_pad_numbers_are_jumpers no)
		(fp_line
			(start -0.508 -0.9398)
			(end -0.508 0.9398)
			(stroke
				(width 0.1524)
				(type default)
			)
			(layer "F.SilkS")
		)
		(fp_line
			(start 0.508 -0.9398)
			(end -0.508 -0.9398)
			(stroke
				(width 0.1524)
				(type default)
			)
			(layer "F.SilkS")
		)
		(fp_rect
			(start -0.508 0.9398)
			(end 0.508 -0.9398)
			(stroke
				(width 0)
				(type default)
			)
			(fill no)
			(layer "F.CrtYd")
		)
		(fp_rect
			(start -0.508 0.9398)
			(end 0.508 -0.9398)
			(stroke
				(width 0)
				(type default)
			)
			(fill no)
			(layer "F.Fab")
		)
		(pad "1" smd custom
			(at 0 -0.4445 270)
			(size 0.1397 0.1397)
			(layers "F.Cu" "F.Mask" "F.Paste")
			(net "BMC_UART_SEL_IN")
			(options
				(clearance outline)
				(anchor circle)
			)
			(primitives
				(gr_poly
					(pts
						(arc
							(start -0.1778 -0.2794)
							(mid -0.249642 -0.249642)
							(end -0.2794 -0.1778)
						)
						(arc
							(start -0.2794 0.1778)
							(mid -0.249642 0.249642)
							(end -0.1778 0.2794)
						)
						(arc
							(start 0.1778 0.2794)
							(mid 0.249642 0.249642)
							(end 0.2794 0.1778)
						)
						(arc
							(start 0.2794 -0.1778)
							(mid 0.249642 -0.249642)
							(end 0.1778 -0.2794)
						)
					)
					(width 0)
					(fill yes)
				)
			)
		)
		(pad "2" smd custom
			(at 0 0.4445 270)
			(size 0.1397 0.1397)
			(layers "F.Cu" "F.Mask" "F.Paste")
			(net "DEBUG_HDR_UART_SEL")
			(options
				(clearance outline)
				(anchor circle)
			)
			(primitives
				(gr_poly
					(pts
						(arc
							(start -0.1778 -0.2794)
							(mid -0.249642 -0.249642)
							(end -0.2794 -0.1778)
						)
						(arc
							(start -0.2794 0.1778)
							(mid -0.249642 0.249642)
							(end -0.1778 0.2794)
						)
						(arc
							(start 0.1778 0.2794)
							(mid 0.249642 0.249642)
							(end 0.2794 0.1778)
						)
						(arc
							(start 0.2794 -0.1778)
							(mid 0.249642 -0.249642)
							(end 0.1778 -0.2794)
						)
					)
					(width 0)
					(fill yes)
				)
			)
		)
	)
	(footprint ""
		(layer "F.Cu")
		(at 39.994332 -161.425128)
		(property "Reference" "R309"
			(at 0 0 0)
			(layer "F.SilkS")
			(hide yes)
			(effects
				(font
					(size 1.27 1.27)
				)
			)
		)
		(property "Value" "4K7R2F-GP"
			(at 0.064008 -3.993896 0)
			(unlocked yes)
			(layer "F.Fab")
			(hide yes)
			(effects
				(font
					(size 1.016 1.016)
					(thickness 0.1524)
				)
			)
		)
		(property "Device Type" "R402H16"
			(at 0.064008 -5.517896 0)
			(unlocked yes)
			(layer "F.Fab")
			(hide yes)
			(effects
				(font
					(size 1.016 1.016)
					(thickness 0.1524)
				)
			)
		)
		(duplicate_pad_numbers_are_jumpers no)
		(fp_line
			(start -0.508 -0.9398)
			(end -0.508 0.9398)
			(stroke
				(width 0.1524)
				(type default)
			)
			(layer "F.SilkS")
		)
		(fp_line
			(start 0.508 -0.9398)
			(end -0.508 -0.9398)
			(stroke
				(width 0.1524)
				(type default)
			)
			(layer "F.SilkS")
		)
		(fp_rect
			(start -0.508 0.9398)
			(end 0.508 -0.9398)
			(stroke
				(width 0)
				(type default)
			)
			(fill no)
			(layer "F.CrtYd")
		)
		(fp_rect
			(start -0.508 0.9398)
			(end 0.508 -0.9398)
			(stroke
				(width 0)
				(type default)
			)
			(fill no)
			(layer "F.Fab")
		)
		(pad "1" smd custom
			(at 0 -0.4445)
			(size 0.1397 0.1397)
			(layers "F.Cu" "F.Mask" "F.Paste")
			(net "P3V3_STBY")
			(options
				(clearance outline)
				(anchor circle)
			)
			(primitives
				(gr_poly
					(pts
						(arc
							(start -0.1778 -0.2794)
							(mid -0.249642 -0.249642)
							(end -0.2794 -0.1778)
						)
						(arc
							(start -0.2794 0.1778)
							(mid -0.249642 0.249642)
							(end -0.1778 0.2794)
						)
						(arc
							(start 0.1778 0.2794)
							(mid 0.249642 0.249642)
							(end 0.2794 0.1778)
						)
						(arc
							(start 0.2794 -0.1778)
							(mid 0.249642 -0.249642)
							(end 0.1778 -0.2794)
						)
					)
					(width 0)
					(fill yes)
				)
			)
		)
		(pad "2" smd custom
			(at 0 0.4445)
			(size 0.1397 0.1397)
			(layers "F.Cu" "F.Mask" "F.Paste")
			(net "BOARD_REV_0")
			(options
				(clearance outline)
				(anchor circle)
			)
			(primitives
				(gr_poly
					(pts
						(arc
							(start -0.1778 -0.2794)
							(mid -0.249642 -0.249642)
							(end -0.2794 -0.1778)
						)
						(arc
							(start -0.2794 0.1778)
							(mid -0.249642 0.249642)
							(end -0.1778 0.2794)
						)
						(arc
							(start 0.1778 0.2794)
							(mid 0.249642 0.249642)
							(end 0.2794 0.1778)
						)
						(arc
							(start 0.2794 -0.1778)
							(mid 0.249642 -0.249642)
							(end 0.1778 -0.2794)
						)
					)
					(width 0)
					(fill yes)
				)
			)
		)
	)
	(footprint ""
		(layer "F.Cu")
		(at 89.468198 -26.4668 90)
		(property "Reference" "D13"
			(at 0 0 90)
			(layer "F.SilkS")
			(hide yes)
			(effects
				(font
					(size 1.27 1.27)
				)
			)
		)
		(property "Value" "PESD5V0S1BL-1-GP"
			(at 1.8923 -1.5621 90)
			(unlocked yes)
			(layer "F.Fab")
			(hide yes)
			(effects
				(font
					(size 1.016 1.016)
					(thickness 0.1524)
				)
			)
		)
		(property "Device Type" "SOD882-10D6-1H20"
			(at 1.8923 -3.0861 90)
			(unlocked yes)
			(layer "F.Fab")
			(hide yes)
			(effects
				(font
					(size 1.016 1.016)
					(thickness 0.1524)
				)
			)
		)
		(duplicate_pad_numbers_are_jumpers no)
		(fp_line
			(start -0.3048 -0.9271)
			(end 0.3048 -0.9271)
			(stroke
				(width 0.254)
				(type default)
			)
			(layer "F.SilkS")
		)
		(fp_rect
			(start -0.2921 0.4953)
			(end 0.2921 -0.4953)
			(stroke
				(width 0)
				(type default)
			)
			(fill no)
			(layer "F.CrtYd")
		)
		(fp_poly
			(pts
				(xy -0.4318 0.8001) (xy -0.4318 -0.266192) (xy -0.2921 -0.266192) (xy -0.2921 0.4953) (xy 0.2921 0.4953)
				(xy 0.2921 -0.4953) (xy -0.2921 -0.4953) (xy -0.2921 -0.2667) (xy -0.4318 -0.2667) (xy -0.4318 -0.8001)
				(xy 0.4318 -0.8001) (xy 0.4318 0.8001)
			)
			(stroke
				(width 0)
				(type default)
			)
			(fill no)
			(layer "F.CrtYd")
		)
		(fp_rect
			(start -0.4318 0.8001)
			(end 0.4318 -0.8001)
			(stroke
				(width 0)
				(type default)
			)
			(fill no)
			(layer "F.Fab")
		)
		(pad "1" smd custom
			(at 0 -0.4445 90)
			(size 0.1143 0.1143)
			(layers "F.Cu" "F.Mask" "F.Paste")
			(net "P5V_VBUS_CONN")
			(options
				(clearance outline)
				(anchor circle)
			)
			(primitives
				(gr_poly
					(pts
						(arc
							(start -0.2032 0.2286)
							(mid -0.275042 0.198842)
							(end -0.3048 0.127)
						)
						(arc
							(start -0.3048 -0.127)
							(mid -0.275042 -0.198842)
							(end -0.2032 -0.2286)
						)
						(arc
							(start 0.2032 -0.2286)
							(mid 0.275042 -0.198842)
							(end 0.3048 -0.127)
						)
						(arc
							(start 0.3048 0.127)
							(mid 0.275042 0.198842)
							(end 0.2032 0.2286)
						)
					)
					(width 0)
					(fill yes)
				)
			)
		)
		(pad "2" smd custom
			(at 0 0.4445 90)
			(size 0.1143 0.1143)
			(layers "F.Cu" "F.Mask" "F.Paste")
			(net "GND")
			(options
				(clearance outline)
				(anchor circle)
			)
			(primitives
				(gr_poly
					(pts
						(arc
							(start 0.2032 -0.2286)
							(mid 0.275042 -0.198842)
							(end 0.3048 -0.127)
						)
						(arc
							(start 0.3048 0.127)
							(mid 0.275042 0.198842)
							(end 0.2032 0.2286)
						)
						(arc
							(start -0.2032 0.2286)
							(mid -0.275042 0.198842)
							(end -0.3048 0.127)
						)
						(arc
							(start -0.3048 -0.127)
							(mid -0.275042 -0.198842)
							(end -0.2032 -0.2286)
						)
					)
					(width 0)
					(fill yes)
				)
			)
		)
	)
	(footprint ""
		(layer "F.Cu")
		(at 37.589968 -130.984244 90)
		(property "Reference" "R377"
			(at 0 0 90)
			(layer "F.SilkS")
			(hide yes)
			(effects
				(font
					(size 1.27 1.27)
				)
			)
		)
		(property "Value" "4K7R2F-GP"
			(at 0.064008 -3.993896 90)
			(unlocked yes)
			(layer "F.Fab")
			(hide yes)
			(effects
				(font
					(size 1.016 1.016)
					(thickness 0.1524)
				)
			)
		)
		(property "Device Type" "R402H16"
			(at 0.064008 -5.517896 90)
			(unlocked yes)
			(layer "F.Fab")
			(hide yes)
			(effects
				(font
					(size 1.016 1.016)
					(thickness 0.1524)
				)
			)
		)
		(duplicate_pad_numbers_are_jumpers no)
		(fp_line
			(start 0.508 -0.9398)
			(end -0.508 -0.9398)
			(stroke
				(width 0.1524)
				(type default)
			)
			(layer "F.SilkS")
		)
		(fp_line
			(start -0.508 -0.9398)
			(end -0.508 0.9398)
			(stroke
				(width 0.1524)
				(type default)
			)
			(layer "F.SilkS")
		)
		(fp_rect
			(start -0.508 0.9398)
			(end 0.508 -0.9398)
			(stroke
				(width 0)
				(type default)
			)
			(fill no)
			(layer "F.CrtYd")
		)
		(fp_rect
			(start -0.508 0.9398)
			(end 0.508 -0.9398)
			(stroke
				(width 0)
				(type default)
			)
			(fill no)
			(layer "F.Fab")
		)
		(pad "1" smd custom
			(at 0 -0.4445 90)
			(size 0.1397 0.1397)
			(layers "F.Cu" "F.Mask" "F.Paste")
			(net "P3V3_STBY")
			(options
				(clearance outline)
				(anchor circle)
			)
			(primitives
				(gr_poly
					(pts
						(arc
							(start -0.1778 -0.2794)
							(mid -0.249642 -0.249642)
							(end -0.2794 -0.1778)
						)
						(arc
							(start -0.2794 0.1778)
							(mid -0.249642 0.249642)
							(end -0.1778 0.2794)
						)
						(arc
							(start 0.1778 0.2794)
							(mid 0.249642 0.249642)
							(end 0.2794 0.1778)
						)
						(arc
							(start 0.2794 -0.1778)
							(mid 0.249642 -0.249642)
							(end 0.1778 -0.2794)
						)
					)
					(width 0)
					(fill yes)
				)
			)
		)
		(pad "2" smd custom
			(at 0 0.4445 90)
			(size 0.1397 0.1397)
			(layers "F.Cu" "F.Mask" "F.Paste")
			(net "BMC_GPIOZ5")
			(options
				(clearance outline)
				(anchor circle)
			)
			(primitives
				(gr_poly
					(pts
						(arc
							(start -0.1778 -0.2794)
							(mid -0.249642 -0.249642)
							(end -0.2794 -0.1778)
						)
						(arc
							(start -0.2794 0.1778)
							(mid -0.249642 0.249642)
							(end -0.1778 0.2794)
						)
						(arc
							(start 0.1778 0.2794)
							(mid 0.249642 0.249642)
							(end 0.2794 0.1778)
						)
						(arc
							(start 0.2794 -0.1778)
							(mid 0.249642 -0.249642)
							(end 0.1778 -0.2794)
						)
					)
					(width 0)
					(fill yes)
				)
			)
		)
	)
	(footprint ""
		(layer "F.Cu")
		(at 99.430332 -18.402046 180)
		(property "Reference" "R38"
			(at 0 0 180)
			(layer "F.SilkS")
			(hide yes)
			(effects
				(font
					(size 1.27 1.27)
				)
			)
		)
		(property "Value" "0R2J-2-GP"
			(at 0.064008 -3.993896 180)
			(unlocked yes)
			(layer "F.Fab")
			(hide yes)
			(effects
				(font
					(size 1.016 1.016)
					(thickness 0.1524)
				)
			)
		)
		(property "Device Type" "R402H16"
			(at 0.064008 -5.517896 180)
			(unlocked yes)
			(layer "F.Fab")
			(hide yes)
			(effects
				(font
					(size 1.016 1.016)
					(thickness 0.1524)
				)
			)
		)
		(duplicate_pad_numbers_are_jumpers no)
		(fp_line
			(start 0.508 -0.9398)
			(end -0.508 -0.9398)
			(stroke
				(width 0.1524)
				(type default)
			)
			(layer "F.SilkS")
		)
		(fp_line
			(start -0.508 -0.9398)
			(end -0.508 0.9398)
			(stroke
				(width 0.1524)
				(type default)
			)
			(layer "F.SilkS")
		)
		(fp_rect
			(start -0.508 0.9398)
			(end 0.508 -0.9398)
			(stroke
				(width 0)
				(type default)
			)
			(fill no)
			(layer "F.CrtYd")
		)
		(fp_rect
			(start -0.508 0.9398)
			(end 0.508 -0.9398)
			(stroke
				(width 0)
				(type default)
			)
			(fill no)
			(layer "F.Fab")
		)
		(pad "1" smd custom
			(at 0 -0.4445 180)
			(size 0.1397 0.1397)
			(layers "F.Cu" "F.Mask" "F.Paste")
			(net "USB_P1_F_DP1")
			(options
				(clearance outline)
				(anchor circle)
			)
			(primitives
				(gr_poly
					(pts
						(arc
							(start -0.1778 -0.2794)
							(mid -0.249642 -0.249642)
							(end -0.2794 -0.1778)
						)
						(arc
							(start -0.2794 0.1778)
							(mid -0.249642 0.249642)
							(end -0.1778 0.2794)
						)
						(arc
							(start 0.1778 0.2794)
							(mid 0.249642 0.249642)
							(end 0.2794 0.1778)
						)
						(arc
							(start 0.2794 -0.1778)
							(mid 0.249642 -0.249642)
							(end 0.1778 -0.2794)
						)
					)
					(width 0)
					(fill yes)
				)
			)
		)
		(pad "2" smd custom
			(at 0 0.4445 180)
			(size 0.1397 0.1397)
			(layers "F.Cu" "F.Mask" "F.Paste")
			(net "USB_P1_DP")
			(options
				(clearance outline)
				(anchor circle)
			)
			(primitives
				(gr_poly
					(pts
						(arc
							(start -0.1778 -0.2794)
							(mid -0.249642 -0.249642)
							(end -0.2794 -0.1778)
						)
						(arc
							(start -0.2794 0.1778)
							(mid -0.249642 0.249642)
							(end -0.1778 0.2794)
						)
						(arc
							(start 0.1778 0.2794)
							(mid 0.249642 0.249642)
							(end 0.2794 0.1778)
						)
						(arc
							(start 0.2794 -0.1778)
							(mid 0.249642 -0.249642)
							(end 0.1778 -0.2794)
						)
					)
					(width 0)
					(fill yes)
				)
			)
		)
	)
)
